(kicad_pcb
	(version 20221018)
	(generator pcbnew)
	(general
    (thickness 1.62)
  )
	(paper "A4")
	(title_block
    (title "ECP5 - Datacenter Secure Control Module (DC-SCM)")
    (date "2024-07-01")
    (rev "1.2.1")
		(comment 9 "footprints 450-458 of 506")
	)
	(layers
    (0 "F.Cu" signal)
    (1 "In1.Cu" power)
    (2 "In2.Cu" signal)
    (3 "In3.Cu" power)
    (4 "In4.Cu" power)
    (5 "In5.Cu" signal)
    (6 "In6.Cu" power)
    (31 "B.Cu" signal)
    (32 "B.Adhes" user "B.Adhesive")
    (33 "F.Adhes" user "F.Adhesive")
    (34 "B.Paste" user)
    (35 "F.Paste" user)
    (36 "B.SilkS" user "B.Silkscreen")
    (37 "F.SilkS" user "F.Silkscreen")
    (38 "B.Mask" user)
    (39 "F.Mask" user)
    (40 "Dwgs.User" user "User.Drawings")
    (41 "Cmts.User" user "User.Comments")
    (42 "Eco1.User" user "User.Eco1")
    (43 "Eco2.User" user "User.Eco2")
    (44 "Edge.Cuts" user)
    (45 "Margin" user)
    (46 "B.CrtYd" user "B.Courtyard")
    (47 "F.CrtYd" user "F.Courtyard")
    (48 "B.Fab" user)
    (49 "F.Fab" user)
  )
	(footprint "antmicro-footprints:R_0402_1005Metric" (layer "B.Cu")
    (at 97.55 89.75)
    (descr "Resistor SMD 0402")
    (tags "resistor SMD 0402")
    (property "Author" "Antmicro")
    (property "License" "Apache-2.0")
    (property "MPN" "CR0402-FX-1022GLF")
    (property "Manufacturer" "Bourns")
    (property "Public" "False")
    (property "Sheetfile" "ethernet.kicad_sch")
    (property "Sheetname" "Ethernet")
    (property "Tolerance" "1%")
    (property "Val" "10k2")
    (property "ki_description" "SMD Chip Resistor")
    (property "ki_keywords" "0402, SMT, RESISTOR, PASSIVE")
    (attr smd)
    (fp_text reference "R12" (at 1.06 -1.015) (layer "B.SilkS")
        (effects (font (size 0.7 0.7) (thickness 0.127)) (justify mirror))
    )
    (fp_text value "R_10k2_0402" (at 0 -1.17) (layer "B.Fab")
        (effects (font (size 1 1) (thickness 0.15)) (justify mirror))
    )
    (fp_text user "License: Apache-2.0" (at -0.95 -5.169 180) (layer "B.Fab") hide
        (effects (font (size 0.7 0.7) (thickness 0.15)) (justify left bottom mirror))
    )
    (fp_text user "${REFERENCE}" (at 0 0) (layer "B.Fab")
        (effects (font (size 0.25 0.25) (thickness 0.04)) (justify mirror))
    )
    (fp_text user "Author: Antmicro" (at -0.95 -4.169 180) (layer "B.Fab") hide
        (effects (font (size 0.7 0.7) (thickness 0.15)) (justify left bottom mirror))
    )
    (fp_rect (start -0.925 0.47) (end 0.925 -0.47)
      (stroke (width 0.05) (type default)) (fill none) (layer "B.CrtYd"))
    (fp_rect (start -0.5 0.25) (end 0.5 -0.25)
      (stroke (width 0.15) (type solid)) (fill none) (layer "B.Fab"))
    (pad "1" smd roundrect (at -0.48 0) (size 0.59 0.64) (layers "B.Cu" "B.Paste" "B.Mask") (roundrect_rratio 0.25)
      (net 165 "/Ethernet/ETH_LED2") (pintype "passive"))
    (pad "2" smd roundrect (at 0.48 0) (size 0.59 0.64) (layers "B.Cu" "B.Paste" "B.Mask") (roundrect_rratio 0.25)
      (net 2 "VCC3V3") (pintype "passive"))
  )
	(footprint "antmicro-footprints:R_0402_1005Metric" (layer "B.Cu")
    (at 96.05 88 -90)
    (descr "Resistor SMD 0402")
    (tags "resistor SMD 0402")
    (property "Author" "Antmicro")
    (property "License" "Apache-2.0")
    (property "MPN" "CR0402-FX-1001GLF")
    (property "Manufacturer" "Bourns")
    (property "Public" "False")
    (property "Sheetfile" "ethernet.kicad_sch")
    (property "Sheetname" "Ethernet")
    (property "Tolerance" "1%")
    (property "Val" "1k")
    (property "ki_description" "SMD Chip Resistor, 1 kohm, ± 1%, 63 mW, 0402 [1005 Metric], Thick Film, General Purpose")
    (property "ki_keywords" "0402, SMT, RESISTOR, PASSIVE")
    (attr smd)
    (fp_text reference "R16" (at 0 1.17 90) (layer "B.SilkS")
        (effects (font (size 0.7 0.7) (thickness 0.127)) (justify mirror))
    )
    (fp_text value "R_1k_0402" (at 0 -1.17 90) (layer "B.Fab")
        (effects (font (size 1 1) (thickness 0.15)) (justify mirror))
    )
    (fp_text user "License: Apache-2.0" (at -0.95 -5.169 90) (layer "B.Fab") hide
        (effects (font (size 0.7 0.7) (thickness 0.15)) (justify left bottom mirror))
    )
    (fp_text user "Author: Antmicro" (at -0.95 -4.169 90) (layer "B.Fab") hide
        (effects (font (size 0.7 0.7) (thickness 0.15)) (justify left bottom mirror))
    )
    (fp_text user "${REFERENCE}" (at 0 0 90) (layer "B.Fab")
        (effects (font (size 0.25 0.25) (thickness 0.04)) (justify mirror))
    )
    (fp_rect (start -0.925 0.47) (end 0.925 -0.47)
      (stroke (width 0.05) (type default)) (fill none) (layer "B.CrtYd"))
    (fp_rect (start -0.5 0.25) (end 0.5 -0.25)
      (stroke (width 0.15) (type solid)) (fill none) (layer "B.Fab"))
    (pad "1" smd roundrect (at -0.48 0 270) (size 0.59 0.64) (layers "B.Cu" "B.Paste" "B.Mask") (roundrect_rratio 0.25)
      (net 680 "Net-(J1-Pad13)") (pintype "passive"))
    (pad "2" smd roundrect (at 0.48 0 270) (size 0.59 0.64) (layers "B.Cu" "B.Paste" "B.Mask") (roundrect_rratio 0.25)
      (net 164 "/Ethernet/ETH_LED1") (pintype "passive"))
  )
	(footprint "antmicro-footprints:C_0402_1005Metric" (layer "B.Cu")
    (at 83.31 97.95 -90)
    (descr "Capacitor SMD 0402")
    (tags "capacitor SMD 0402")
    (property "Author" "Antmicro")
    (property "Dielectric" "X5R")
    (property "License" "Apache-2.0")
    (property "MPN" "GRM155R61H104KE14D")
    (property "Manufacturer" "Murata")
    (property "Public" "False")
    (property "Sheetfile" "interfaces.kicad_sch")
    (property "Sheetname" "Interfaces")
    (property "Val" "100n")
    (property "Voltage" "50V")
    (property "ki_description" "SMD Multilayer Ceramic Capacitor, 0.1 µF, 50 V, 0402 [1005 Metric], ± 10%, X5R, GRM Series")
    (property "ki_keywords" "0402, SMT, CAPACITOR, PASSIVE, CERAMIC, MLCC")
    (attr smd)
    (fp_text reference "C54" (at -0.05 -1.21 90) (layer "B.SilkS")
        (effects (font (size 0.7 0.7) (thickness 0.127)) (justify mirror))
    )
    (fp_text value "C_100n_0402" (at 0 -1.17 90) (layer "B.Fab")
        (effects (font (size 1 1) (thickness 0.15)) (justify mirror))
    )
    (fp_text user "License: Apache-2.0" (at -0.939 -5.799 90) (layer "B.Fab") hide
        (effects (font (size 0.7 0.7) (thickness 0.15)) (justify left bottom mirror))
    )
    (fp_text user "${REFERENCE}" (at 0 0 90) (layer "B.Fab")
        (effects (font (size 0.25 0.25) (thickness 0.04)) (justify mirror))
    )
    (fp_text user "Author: Antmicro" (at -0.939 -3.399 90) (layer "B.Fab") hide
        (effects (font (size 0.7 0.7) (thickness 0.15)) (justify left bottom mirror))
    )
    (fp_rect (start -0.925 0.47) (end 0.925 -0.47)
      (stroke (width 0.05) (type default)) (fill none) (layer "B.CrtYd"))
    (fp_line (start -0.494 -0.248) (end -0.494 0.25)
      (stroke (width 0.15) (type solid)) (layer "B.Fab"))
    (fp_line (start -0.494 0.25) (end 0.504 0.25)
      (stroke (width 0.15) (type solid)) (layer "B.Fab"))
    (fp_line (start 0.504 -0.248) (end -0.494 -0.248)
      (stroke (width 0.15) (type solid)) (layer "B.Fab"))
    (fp_line (start 0.504 0.25) (end 0.504 -0.248)
      (stroke (width 0.15) (type solid)) (layer "B.Fab"))
    (pad "1" smd roundrect (at -0.48 0 270) (size 0.59 0.64) (layers "B.Cu" "B.Paste" "B.Mask") (roundrect_rratio 0.25)
      (net 1 "GND") (pintype "passive"))
    (pad "2" smd roundrect (at 0.48 0 270) (size 0.59 0.64) (layers "B.Cu" "B.Paste" "B.Mask") (roundrect_rratio 0.25)
      (net 219 "Net-(U6-VDDIM)") (pintype "passive"))
  )
	(footprint "antmicro-footprints:C_0402_1005Metric" (layer "B.Cu")
    (at 128.6 124.6 90)
    (descr "Capacitor SMD 0402")
    (tags "capacitor SMD 0402")
    (property "Author" "Antmicro")
    (property "Dielectric" "X5R")
    (property "License" "Apache-2.0")
    (property "MPN" "GRM155R61H104KE14D")
    (property "Manufacturer" "Murata")
    (property "Public" "False")
    (property "Sheetfile" "interfaces.kicad_sch")
    (property "Sheetname" "Interfaces")
    (property "Val" "100n")
    (property "Voltage" "50V")
    (property "ki_description" "SMD Multilayer Ceramic Capacitor, 0.1 µF, 50 V, 0402 [1005 Metric], ± 10%, X5R, GRM Series")
    (property "ki_keywords" "0402, SMT, CAPACITOR, PASSIVE, CERAMIC, MLCC")
    (attr smd)
    (fp_text reference "C60" (at 0.025 1.01 90) (layer "B.SilkS")
        (effects (font (size 0.7 0.7) (thickness 0.127)) (justify mirror))
    )
    (fp_text value "C_100n_0402" (at 0 -1.17 90) (layer "B.Fab")
        (effects (font (size 1 1) (thickness 0.15)) (justify mirror))
    )
    (fp_text user "License: Apache-2.0" (at -0.939 -5.799 270) (layer "B.Fab") hide
        (effects (font (size 0.7 0.7) (thickness 0.15)) (justify left bottom mirror))
    )
    (fp_text user "${REFERENCE}" (at 0 0 90) (layer "B.Fab")
        (effects (font (size 0.25 0.25) (thickness 0.04)) (justify mirror))
    )
    (fp_text user "Author: Antmicro" (at -0.939 -3.399 270) (layer "B.Fab") hide
        (effects (font (size 0.7 0.7) (thickness 0.15)) (justify left bottom mirror))
    )
    (fp_rect (start -0.925 0.47) (end 0.925 -0.47)
      (stroke (width 0.05) (type default)) (fill none) (layer "B.CrtYd"))
    (fp_line (start -0.494 -0.248) (end -0.494 0.25)
      (stroke (width 0.15) (type solid)) (layer "B.Fab"))
    (fp_line (start -0.494 0.25) (end 0.504 0.25)
      (stroke (width 0.15) (type solid)) (layer "B.Fab"))
    (fp_line (start 0.504 -0.248) (end -0.494 -0.248)
      (stroke (width 0.15) (type solid)) (layer "B.Fab"))
    (fp_line (start 0.504 0.25) (end 0.504 -0.248)
      (stroke (width 0.15) (type solid)) (layer "B.Fab"))
    (pad "1" smd roundrect (at -0.48 0 90) (size 0.59 0.64) (layers "B.Cu" "B.Paste" "B.Mask") (roundrect_rratio 0.25)
      (net 2 "VCC3V3") (pintype "passive"))
    (pad "2" smd roundrect (at 0.48 0 90) (size 0.59 0.64) (layers "B.Cu" "B.Paste" "B.Mask") (roundrect_rratio 0.25)
      (net 1 "GND") (pintype "passive"))
  )
	(footprint "antmicro-footprints:R_0402_1005Metric" (layer "B.Cu")
    (at 127.425 124.625 -90)
    (descr "Resistor SMD 0402")
    (tags "resistor SMD 0402")
    (property "Author" "Antmicro")
    (property "License" "Apache-2.0")
    (property "MPN" "CR0402-FX-1001GLF")
    (property "Manufacturer" "Bourns")
    (property "Public" "False")
    (property "Sheetfile" "interfaces.kicad_sch")
    (property "Sheetname" "Interfaces")
    (property "Tolerance" "1%")
    (property "Val" "1k")
    (property "ki_description" "SMD Chip Resistor, 1 kohm, ± 1%, 63 mW, 0402 [1005 Metric], Thick Film, General Purpose")
    (property "ki_keywords" "0402, SMT, RESISTOR, PASSIVE")
    (attr smd)
    (fp_text reference "R74" (at -2.225 0 -90) (layer "B.SilkS")
        (effects (font (size 0.7 0.7) (thickness 0.127)) (justify mirror))
    )
    (fp_text value "R_1k_0402" (at 0 -1.17 -90) (layer "B.Fab")
        (effects (font (size 1 1) (thickness 0.15)) (justify mirror))
    )
    (fp_text user "${REFERENCE}" (at 0 0 -90) (layer "B.Fab")
        (effects (font (size 0.25 0.25) (thickness 0.04)) (justify mirror))
    )
    (fp_text user "License: Apache-2.0" (at -0.95 -5.169 90) (layer "B.Fab") hide
        (effects (font (size 0.7 0.7) (thickness 0.15)) (justify left bottom mirror))
    )
    (fp_text user "Author: Antmicro" (at -0.95 -4.169 90) (layer "B.Fab") hide
        (effects (font (size 0.7 0.7) (thickness 0.15)) (justify left bottom mirror))
    )
    (fp_rect (start -0.925 0.47) (end 0.925 -0.47)
      (stroke (width 0.05) (type default)) (fill none) (layer "B.CrtYd"))
    (fp_rect (start -0.5 0.25) (end 0.5 -0.25)
      (stroke (width 0.15) (type solid)) (fill none) (layer "B.Fab"))
    (pad "1" smd roundrect (at -0.48 0 270) (size 0.59 0.64) (layers "B.Cu" "B.Paste" "B.Mask") (roundrect_rratio 0.25)
      (net 11 "VCC5V0") (pintype "passive"))
    (pad "2" smd roundrect (at 0.48 0 270) (size 0.59 0.64) (layers "B.Cu" "B.Paste" "B.Mask") (roundrect_rratio 0.25)
      (net 404 "Net-(U8-VBUS)") (pintype "passive"))
  )
	(footprint "antmicro-footprints:C_0402_1005Metric" (layer "B.Cu")
    (at 126.625 130.7 180)
    (descr "Capacitor SMD 0402")
    (tags "capacitor SMD 0402")
    (property "Author" "Antmicro")
    (property "Dielectric" "X5R")
    (property "License" "Apache-2.0")
    (property "MPN" "GRM155R61H104KE14D")
    (property "Manufacturer" "Murata")
    (property "Public" "False")
    (property "Sheetfile" "interfaces.kicad_sch")
    (property "Sheetname" "Interfaces")
    (property "Val" "100n")
    (property "Voltage" "50V")
    (property "ki_description" "SMD Multilayer Ceramic Capacitor, 0.1 µF, 50 V, 0402 [1005 Metric], ± 10%, X5R, GRM Series")
    (property "ki_keywords" "0402, SMT, CAPACITOR, PASSIVE, CERAMIC, MLCC")
    (attr smd)
    (fp_text reference "C73" (at -0.105 -1.035) (layer "B.SilkS")
        (effects (font (size 0.7 0.7) (thickness 0.127)) (justify mirror))
    )
    (fp_text value "C_100n_0402" (at 0 -1.17) (layer "B.Fab")
        (effects (font (size 1 1) (thickness 0.15)) (justify mirror))
    )
    (fp_text user "Author: Antmicro" (at -0.939 -3.399) (layer "B.Fab") hide
        (effects (font (size 0.7 0.7) (thickness 0.15)) (justify left bottom mirror))
    )
    (fp_text user "${REFERENCE}" (at 0 0) (layer "B.Fab")
        (effects (font (size 0.25 0.25) (thickness 0.04)) (justify mirror))
    )
    (fp_text user "License: Apache-2.0" (at -0.939 -5.799) (layer "B.Fab") hide
        (effects (font (size 0.7 0.7) (thickness 0.15)) (justify left bottom mirror))
    )
    (fp_rect (start -0.925 0.47) (end 0.925 -0.47)
      (stroke (width 0.05) (type default)) (fill none) (layer "B.CrtYd"))
    (fp_line (start -0.494 -0.248) (end -0.494 0.25)
      (stroke (width 0.15) (type solid)) (layer "B.Fab"))
    (fp_line (start -0.494 0.25) (end 0.504 0.25)
      (stroke (width 0.15) (type solid)) (layer "B.Fab"))
    (fp_line (start 0.504 -0.248) (end -0.494 -0.248)
      (stroke (width 0.15) (type solid)) (layer "B.Fab"))
    (fp_line (start 0.504 0.25) (end 0.504 -0.248)
      (stroke (width 0.15) (type solid)) (layer "B.Fab"))
    (pad "1" smd roundrect (at -0.48 0 180) (size 0.59 0.64) (layers "B.Cu" "B.Paste" "B.Mask") (roundrect_rratio 0.25)
      (net 1 "GND") (pintype "passive"))
    (pad "2" smd roundrect (at 0.48 0 180) (size 0.59 0.64) (layers "B.Cu" "B.Paste" "B.Mask") (roundrect_rratio 0.25)
      (net 221 "Net-(U8-VDDA1.8)") (pintype "passive"))
  )
	(footprint "antmicro-footprints:C_0402_1005Metric" (layer "B.Cu")
    (at 122.525 130.7)
    (descr "Capacitor SMD 0402")
    (tags "capacitor SMD 0402")
    (property "Author" "Antmicro")
    (property "Dielectric" "")
    (property "License" "Apache-2.0")
    (property "MPN" "GRM155R61A475MEAAD")
    (property "Manufacturer" "Murata")
    (property "Public" "False")
    (property "Sheetfile" "interfaces.kicad_sch")
    (property "Sheetname" "Interfaces")
    (property "Val" "4u7")
    (property "Voltage" "")
    (property "ki_description" "SMD Multilayer Ceramic Capacitor, 4.7 µF, 10 V, 0402 [1005 Metric], ± 20%, X5R, GRM Series")
    (property "ki_keywords" "0402, SMT, CAPACITOR, PASSIVE")
    (attr smd)
    (fp_text reference "C75" (at 0.035 1.415) (layer "B.SilkS")
        (effects (font (size 0.7 0.7) (thickness 0.127)) (justify mirror))
    )
    (fp_text value "C_4u7_0402" (at 0 -1.17) (layer "B.Fab")
        (effects (font (size 1 1) (thickness 0.15)) (justify mirror))
    )
    (fp_text user "Author: Antmicro" (at -0.939 -3.399 180) (layer "B.Fab") hide
        (effects (font (size 0.7 0.7) (thickness 0.15)) (justify left bottom mirror))
    )
    (fp_text user "${REFERENCE}" (at 0 0) (layer "B.Fab")
        (effects (font (size 0.25 0.25) (thickness 0.04)) (justify mirror))
    )
    (fp_text user "License: Apache-2.0" (at -0.939 -5.799 180) (layer "B.Fab") hide
        (effects (font (size 0.7 0.7) (thickness 0.15)) (justify left bottom mirror))
    )
    (fp_rect (start -0.925 0.47) (end 0.925 -0.47)
      (stroke (width 0.05) (type default)) (fill none) (layer "B.CrtYd"))
    (fp_line (start -0.494 -0.248) (end -0.494 0.25)
      (stroke (width 0.15) (type solid)) (layer "B.Fab"))
    (fp_line (start -0.494 0.25) (end 0.504 0.25)
      (stroke (width 0.15) (type solid)) (layer "B.Fab"))
    (fp_line (start 0.504 -0.248) (end -0.494 -0.248)
      (stroke (width 0.15) (type solid)) (layer "B.Fab"))
    (fp_line (start 0.504 0.25) (end 0.504 -0.248)
      (stroke (width 0.15) (type solid)) (layer "B.Fab"))
    (pad "1" smd roundrect (at -0.48 0) (size 0.59 0.64) (layers "B.Cu" "B.Paste" "B.Mask") (roundrect_rratio 0.25)
      (net 1 "GND") (pintype "passive"))
    (pad "2" smd roundrect (at 0.48 0) (size 0.59 0.64) (layers "B.Cu" "B.Paste" "B.Mask") (roundrect_rratio 0.25)
      (net 227 "Net-(C71-Pad1)") (pintype "passive"))
  )
	(footprint "antmicro-footprints:C_0402_1005Metric" (layer "B.Cu")
    (at 124.675 130.7)
    (descr "Capacitor SMD 0402")
    (tags "capacitor SMD 0402")
    (property "Author" "Antmicro")
    (property "Dielectric" "")
    (property "License" "Apache-2.0")
    (property "MPN" "GRM155R61A475MEAAD")
    (property "Manufacturer" "Murata")
    (property "Public" "False")
    (property "Sheetfile" "interfaces.kicad_sch")
    (property "Sheetname" "Interfaces")
    (property "Val" "4u7")
    (property "Voltage" "")
    (property "ki_description" "SMD Multilayer Ceramic Capacitor, 4.7 µF, 10 V, 0402 [1005 Metric], ± 20%, X5R, GRM Series")
    (property "ki_keywords" "0402, SMT, CAPACITOR, PASSIVE")
    (attr smd)
    (fp_text reference "C66" (at 0.035 1.025) (layer "B.SilkS")
        (effects (font (size 0.7 0.7) (thickness 0.127)) (justify mirror))
    )
    (fp_text value "C_4u7_0402" (at 0 -1.17) (layer "B.Fab")
        (effects (font (size 1 1) (thickness 0.15)) (justify mirror))
    )
    (fp_text user "License: Apache-2.0" (at -0.939 -5.799 180) (layer "B.Fab") hide
        (effects (font (size 0.7 0.7) (thickness 0.15)) (justify left bottom mirror))
    )
    (fp_text user "${REFERENCE}" (at 0 0) (layer "B.Fab")
        (effects (font (size 0.25 0.25) (thickness 0.04)) (justify mirror))
    )
    (fp_text user "Author: Antmicro" (at -0.939 -3.399 180) (layer "B.Fab") hide
        (effects (font (size 0.7 0.7) (thickness 0.15)) (justify left bottom mirror))
    )
    (fp_rect (start -0.925 0.47) (end 0.925 -0.47)
      (stroke (width 0.05) (type default)) (fill none) (layer "B.CrtYd"))
    (fp_line (start -0.494 -0.248) (end -0.494 0.25)
      (stroke (width 0.15) (type solid)) (layer "B.Fab"))
    (fp_line (start -0.494 0.25) (end 0.504 0.25)
      (stroke (width 0.15) (type solid)) (layer "B.Fab"))
    (fp_line (start 0.504 -0.248) (end -0.494 -0.248)
      (stroke (width 0.15) (type solid)) (layer "B.Fab"))
    (fp_line (start 0.504 0.25) (end 0.504 -0.248)
      (stroke (width 0.15) (type solid)) (layer "B.Fab"))
    (pad "1" smd roundrect (at -0.48 0) (size 0.59 0.64) (layers "B.Cu" "B.Paste" "B.Mask") (roundrect_rratio 0.25)
      (net 1 "GND") (pintype "passive"))
    (pad "2" smd roundrect (at 0.48 0) (size 0.59 0.64) (layers "B.Cu" "B.Paste" "B.Mask") (roundrect_rratio 0.25)
      (net 221 "Net-(U8-VDDA1.8)") (pintype "passive"))
  )
	(footprint "antmicro-footprints:C_0402_1005Metric" (layer "B.Cu")
    (at 122.515 128.17 180)
    (descr "Capacitor SMD 0402")
    (tags "capacitor SMD 0402")
    (property "Author" "Antmicro")
    (property "Dielectric" "X5R")
    (property "License" "Apache-2.0")
    (property "MPN" "GRM155R61H104KE14D")
    (property "Manufacturer" "Murata")
    (property "Public" "False")
    (property "Sheetfile" "interfaces.kicad_sch")
    (property "Sheetname" "Interfaces")
    (property "Val" "100n")
    (property "Voltage" "50V")
    (property "ki_description" "SMD Multilayer Ceramic Capacitor, 0.1 µF, 50 V, 0402 [1005 Metric], ± 10%, X5R, GRM Series")
    (property "ki_keywords" "0402, SMT, CAPACITOR, PASSIVE, CERAMIC, MLCC")
    (attr smd)
    (fp_text reference "C63" (at 2.01 0.03) (layer "B.SilkS")
        (effects (font (size 0.7 0.7) (thickness 0.127)) (justify mirror))
    )
    (fp_text value "C_100n_0402" (at 0 -1.17) (layer "B.Fab")
        (effects (font (size 1 1) (thickness 0.15)) (justify mirror))
    )
    (fp_text user "${REFERENCE}" (at 0 0) (layer "B.Fab")
        (effects (font (size 0.25 0.25) (thickness 0.04)) (justify mirror))
    )
    (fp_text user "Author: Antmicro" (at -0.939 -3.399) (layer "B.Fab") hide
        (effects (font (size 0.7 0.7) (thickness 0.15)) (justify left bottom mirror))
    )
    (fp_text user "License: Apache-2.0" (at -0.939 -5.799) (layer "B.Fab") hide
        (effects (font (size 0.7 0.7) (thickness 0.15)) (justify left bottom mirror))
    )
    (fp_rect (start -0.925 0.47) (end 0.925 -0.47)
      (stroke (width 0.05) (type default)) (fill none) (layer "B.CrtYd"))
    (fp_line (start -0.494 -0.248) (end -0.494 0.25)
      (stroke (width 0.15) (type solid)) (layer "B.Fab"))
    (fp_line (start -0.494 0.25) (end 0.504 0.25)
      (stroke (width 0.15) (type solid)) (layer "B.Fab"))
    (fp_line (start 0.504 -0.248) (end -0.494 -0.248)
      (stroke (width 0.15) (type solid)) (layer "B.Fab"))
    (fp_line (start 0.504 0.25) (end 0.504 -0.248)
      (stroke (width 0.15) (type solid)) (layer "B.Fab"))
    (pad "1" smd roundrect (at -0.48 0 180) (size 0.59 0.64) (layers "B.Cu" "B.Paste" "B.Mask") (roundrect_rratio 0.25)
      (net 2 "VCC3V3") (pintype "passive"))
    (pad "2" smd roundrect (at 0.48 0 180) (size 0.59 0.64) (layers "B.Cu" "B.Paste" "B.Mask") (roundrect_rratio 0.25)
      (net 1 "GND") (pintype "passive"))
  )
)
